(kicad_pcb
	(version 20241229)
	(generator "pcbnew")
	(generator_version "9.0")
	(general
		(thickness 1.61)
		(legacy_teardrops no)
	)
	(paper "A3")
	(title_block
		(title "RDIMM DDR5 Tester")
		(date "2026-05-21")
		(rev "2.2.0")
		(company "Antmicro")
		(comment 9 "footprint 119 of 796 (U34), pads 68-132 of 676")
	)
	(layers
		(0 "F.Cu" signal)
		(4 "In1.Cu" power)
		(6 "In2.Cu" mixed)
		(8 "In3.Cu" power)
		(10 "In4.Cu" mixed)
		(12 "In5.Cu" power)
		(14 "In6.Cu" mixed)
		(16 "In7.Cu" power)
		(18 "In8.Cu" power)
		(20 "In9.Cu" mixed)
		(22 "In10.Cu" power)
		(2 "B.Cu" signal)
		(9 "F.Adhes" user "F.Adhesive")
		(11 "B.Adhes" user "B.Adhesive")
		(13 "F.Paste" user)
		(15 "B.Paste" user)
		(5 "F.SilkS" user "F.Silkscreen")
		(7 "B.SilkS" user "B.Silkscreen")
		(1 "F.Mask" user)
		(3 "B.Mask" user)
		(17 "Dwgs.User" user "User.Drawings")
		(19 "Cmts.User" user "User.Comments")
		(21 "Eco1.User" user "User.Eco1")
		(23 "Eco2.User" user "User.Eco2")
		(25 "Edge.Cuts" user)
		(27 "Margin" user)
		(31 "F.CrtYd" user "F.Courtyard")
		(29 "B.CrtYd" user "B.Courtyard")
		(35 "F.Fab" user)
		(33 "B.Fab" user)
	)
	(footprint "antmicro-footprints:BGA-676_27x27mm_Layout26x26_P1x1mm_FFVB676"
		(layer "F.Cu")
		(at 188.5 152.5 90)
		(property "Reference" "U34"
			(at -14.72 12.46 180)
			(layer "F.SilkS")
			(effects
				(font
					(size 0.7 0.7)
					(thickness 0.15)
				)
				(justify left bottom)
			)
		)
		(property "Value" "XCAU25P-2FFVB676I"
			(at 0 15.5 90)
			(layer "F.Fab")
			(effects
				(font
					(size 0.7 0.7)
					(thickness 0.15)
				)
				(justify left bottom)
			)
		)
		(property "Datasheet" "https://docs.xilinx.com/viewer/book-attachment/2PXOpPtpaABIt0fkzeBLnw/hvbsEUaOT0OxFhln7VEVyA"
			(at 0 0 90)
			(layer "F.Fab")
			(hide yes)
			(effects
				(font
					(size 1.27 1.27)
					(thickness 0.15)
				)
			)
		)
		(property "MPN" "XCAU25P-2FFVB676I"
			(at 0 0 90)
			(unlocked yes)
			(layer "F.Fab")
			(hide yes)
			(effects
				(font
					(size 1 1)
					(thickness 0.15)
				)
			)
		)
		(property "Manufacturer" "AMD-Xilinx"
			(at 0 0 90)
			(unlocked yes)
			(layer "F.Fab")
			(hide yes)
			(effects
				(font
					(size 1 1)
					(thickness 0.15)
				)
			)
		)
		(property "Author" "Antmicro"
			(at 0 0 90)
			(unlocked yes)
			(layer "F.Fab")
			(hide yes)
			(effects
				(font
					(size 1 1)
					(thickness 0.15)
				)
			)
		)
		(property "License" "Apache-2.0"
			(at 0 0 90)
			(unlocked yes)
			(layer "F.Fab")
			(hide yes)
			(effects
				(font
					(size 1 1)
					(thickness 0.15)
				)
			)
		)
		(sheetname "/FPGA Config/")
		(sheetfile "fpga-config.kicad_sch")
		(attr smd)
		(pad "AB16" smd circle
			(at 2.5 8.5 90)
			(size 0.5 0.5)
			(layers "F.Cu" "F.Mask" "F.Paste")
			(net 812 "Heater_PWM")
			(pinfunction "IO_L6N_HDGC_AD6N_84")
			(pintype "bidirectional")
			(die_length 12.413)
			(solder_mask_margin 0.075)
		)
		(pad "AB17" smd circle
			(at 3.5 8.5 90)
			(size 0.5 0.5)
			(layers "F.Cu" "F.Mask" "F.Paste")
			(net 178 "/DDR5 RDIMM/A.DQS5_P")
			(pinfunction "IO_L22P_T3U_N6_DBC_AD0P_64")
			(pintype "bidirectional")
			(die_length 15.653)
			(solder_mask_margin 0.075)
		)
		(pad "AB18" smd circle
			(at 4.5 8.5 90)
			(size 0.5 0.5)
			(layers "F.Cu" "F.Mask" "F.Paste")
			(net 687 "VDDQ")
			(pinfunction "VCCO_64")
			(pintype "passive")
			(solder_mask_margin 0.075)
		)
		(pad "AB19" smd circle
			(at 5.5 8.5 90)
			(size 0.5 0.5)
			(layers "F.Cu" "F.Mask" "F.Paste")
			(net 130 "/DDR5 RDIMM/A.DQ2")
			(pinfunction "IO_L20N_T3L_N3_AD1N_64")
			(pintype "bidirectional")
			(die_length 12.739)
			(solder_mask_margin 0.075)
		)
		(pad "AB20" smd circle
			(at 6.5 8.5 90)
			(size 0.5 0.5)
			(layers "F.Cu" "F.Mask" "F.Paste")
			(net 131 "/DDR5 RDIMM/A.DQ3")
			(pinfunction "IO_L21N_T3L_N5_AD8N_64")
			(pintype "bidirectional")
			(die_length 15.087)
			(solder_mask_margin 0.075)
		)
		(pad "AB21" smd circle
			(at 7.5 8.5 90)
			(size 0.5 0.5)
			(layers "F.Cu" "F.Mask" "F.Paste")
			(net 149 "/DDR5 RDIMM/A.DQ22")
			(pinfunction "IO_L12P_T1U_N10_GC_64")
			(pintype "bidirectional")
			(die_length 13.162)
			(solder_mask_margin 0.075)
		)
		(pad "AB22" smd circle
			(at 8.5 8.5 90)
			(size 0.5 0.5)
			(layers "F.Cu" "F.Mask" "F.Paste")
			(net 208 "/DDR5 RDIMM/A.DQS7_N")
			(pinfunction "IO_L10N_T1U_N7_QBC_AD4N_64")
			(pintype "bidirectional")
			(die_length 13.098)
			(solder_mask_margin 0.075)
		)
		(pad "AB23" smd circle
			(at 9.5 8.5 90)
			(size 0.5 0.5)
			(layers "F.Cu" "F.Mask" "F.Paste")
			(net 1 "GND")
			(pinfunction "GND")
			(pintype "passive")
			(solder_mask_margin 0.075)
		)
		(pad "AB24" smd circle
			(at 10.5 8.5 90)
			(size 0.5 0.5)
			(layers "F.Cu" "F.Mask" "F.Paste")
			(net 166 "/DDR5 RDIMM/A.DQ31")
			(pinfunction "IO_L6P_T0U_N10_AD6P_64")
			(pintype "bidirectional")
			(die_length 12.857)
			(solder_mask_margin 0.075)
		)
		(pad "AB25" smd circle
			(at 11.5 8.5 90)
			(size 0.5 0.5)
			(layers "F.Cu" "F.Mask" "F.Paste")
			(net 63 "/DDR5 RDIMM/A.DQ24")
			(pinfunction "IO_L2P_T0L_N2_64")
			(pintype "bidirectional")
			(die_length 12.779)
			(solder_mask_margin 0.075)
		)
		(pad "AB26" smd circle
			(at 12.5 8.5 90)
			(size 0.5 0.5)
			(layers "F.Cu" "F.Mask" "F.Paste")
			(net 154 "/DDR5 RDIMM/A.DQ26")
			(pinfunction "IO_L2N_T0L_N3_64")
			(pintype "bidirectional")
			(die_length 13.643)
			(solder_mask_margin 0.075)
		)
		(pad "AC1" smd circle
			(at -12.5 9.5 90)
			(size 0.5 0.5)
			(layers "F.Cu" "F.Mask" "F.Paste")
			(net 1 "GND")
			(pinfunction "GND")
			(pintype "passive")
			(solder_mask_margin 0.075)
		)
		(pad "AC2" smd circle
			(at -11.5 9.5 90)
			(size 0.5 0.5)
			(layers "F.Cu" "F.Mask" "F.Paste")
			(net 1 "GND")
			(pinfunction "GND")
			(pintype "passive")
			(solder_mask_margin 0.075)
		)
		(pad "AC3" smd circle
			(at -10.5 9.5 90)
			(size 0.5 0.5)
			(layers "F.Cu" "F.Mask" "F.Paste")
			(net 1 "GND")
			(pinfunction "GND")
			(pintype "passive")
			(solder_mask_margin 0.075)
		)
		(pad "AC4" smd circle
			(at -9.5 9.5 90)
			(size 0.5 0.5)
			(layers "F.Cu" "F.Mask" "F.Paste")
			(net 568 "/FPGA MGT Interface/GTY_224_TX3_N")
			(pinfunction "MGTYTXN3_224")
			(pintype "output")
			(die_length 12.023)
			(solder_mask_margin 0.075)
		)
		(pad "AC5" smd circle
			(at -8.5 9.5 90)
			(size 0.5 0.5)
			(layers "F.Cu" "F.Mask" "F.Paste")
			(net 566 "/FPGA MGT Interface/GTY_224_TX3_P")
			(pinfunction "MGTYTXP3_224")
			(pintype "output")
			(die_length 11.995)
			(solder_mask_margin 0.075)
		)
		(pad "AC6" smd circle
			(at -7.5 9.5 90)
			(size 0.5 0.5)
			(layers "F.Cu" "F.Mask" "F.Paste")
			(net 1 "GND")
			(pinfunction "GND")
			(pintype "passive")
			(solder_mask_margin 0.075)
		)
		(pad "AC7" smd circle
			(at -6.5 9.5 90)
			(size 0.5 0.5)
			(layers "F.Cu" "F.Mask" "F.Paste")
			(net 820 "+0V9_MGTAVCC")
			(pinfunction "MGTAVCC_R")
			(pintype "passive")
			(solder_mask_margin 0.075)
		)
		(pad "AC8" smd circle
			(at -5.5 9.5 90)
			(size 0.5 0.5)
			(layers "F.Cu" "F.Mask" "F.Paste")
			(net 1 "GND")
			(pinfunction "GND")
			(pintype "passive")
			(solder_mask_margin 0.075)
		)
		(pad "AC9" smd circle
			(at -4.5 9.5 90)
			(size 0.5 0.5)
			(layers "F.Cu" "F.Mask" "F.Paste")
			(net 1 "GND")
			(pinfunction "GND")
			(pintype "passive")
			(solder_mask_margin 0.075)
		)
		(pad "AC10" smd circle
			(at -3.5 9.5 90)
			(size 0.5 0.5)
			(layers "F.Cu" "F.Mask" "F.Paste")
			(net 1 "GND")
			(pinfunction "GND")
			(pintype "passive")
			(solder_mask_margin 0.075)
		)
		(pad "AC11" smd circle
			(at -2.5 9.5 90)
			(size 0.5 0.5)
			(layers "F.Cu" "F.Mask" "F.Paste")
			(net 353 "/FPGA Config/FLASH.IO2")
			(pinfunction "D02_0")
			(pintype "bidirectional")
			(die_length 16.69)
			(solder_mask_margin 0.075)
		)
		(pad "AC12" smd circle
			(at -1.5 9.5 90)
			(size 0.5 0.5)
			(layers "F.Cu" "F.Mask" "F.Paste")
			(net 352 "/FPGA Config/FLASH.IO1")
			(pinfunction "D01_DIN_0")
			(pintype "bidirectional")
			(die_length 16.061)
			(solder_mask_margin 0.075)
		)
		(pad "AC13" smd circle
			(at -0.5 9.5 90)
			(size 0.5 0.5)
			(layers "F.Cu" "F.Mask" "F.Paste")
			(net 481 "unconnected-(U34F-IO_L5P_HDGC_AD7P_84-PadAC13)")
			(pinfunction "IO_L5P_HDGC_AD7P_84")
			(pintype "bidirectional+no_connect")
			(die_length 13.414)
			(solder_mask_margin 0.075)
		)
		(pad "AC14" smd circle
			(at 0.5 9.5 90)
			(size 0.5 0.5)
			(layers "F.Cu" "F.Mask" "F.Paste")
			(net 466 "unconnected-(U34F-IO_L5N_HDGC_AD7N_84-PadAC14)")
			(pinfunction "IO_L5N_HDGC_AD7N_84")
			(pintype "bidirectional+no_connect")
			(die_length 13.472)
			(solder_mask_margin 0.075)
		)
		(pad "AC15" smd circle
			(at 1.5 9.5 90)
			(size 0.5 0.5)
			(layers "F.Cu" "F.Mask" "F.Paste")
			(net 151 "+3V3")
			(pinfunction "VCCO_84")
			(pintype "power_in")
			(solder_mask_margin 0.075)
		)
		(pad "AC16" smd circle
			(at 2.5 9.5 90)
			(size 0.5 0.5)
			(layers "F.Cu" "F.Mask" "F.Paste")
			(net 483 "unconnected-(U34B-IO_T3U_N12_64-PadAC16)")
			(pinfunction "IO_T3U_N12_64")
			(pintype "bidirectional+no_connect")
			(die_length 16.232)
			(solder_mask_margin 0.075)
		)
		(pad "AC17" smd circle
			(at 3.5 9.5 90)
			(size 0.5 0.5)
			(layers "F.Cu" "F.Mask" "F.Paste")
			(net 177 "/DDR5 RDIMM/A.DQS5_N")
			(pinfunction "IO_L22N_T3U_N7_DBC_AD0N_64")
			(pintype "bidirectional")
			(die_length 15.676)
			(solder_mask_margin 0.075)
		)
		(pad "AC18" smd circle
			(at 4.5 9.5 90)
			(size 0.5 0.5)
			(layers "F.Cu" "F.Mask" "F.Paste")
			(net 182 "/DDR5 RDIMM/A.DQS6_P")
			(pinfunction "IO_L16P_T2U_N6_QBC_AD3P_64")
			(pintype "bidirectional")
			(die_length 15.141)
			(solder_mask_margin 0.075)
		)
		(pad "AC19" smd circle
			(at 5.5 9.5 90)
			(size 0.5 0.5)
			(layers "F.Cu" "F.Mask" "F.Paste")
			(net 136 "/DDR5 RDIMM/A.DQ10")
			(pinfunction "IO_L14P_T2L_N2_GC_64")
			(pintype "bidirectional")
			(die_length 14.095)
			(solder_mask_margin 0.075)
		)
		(pad "AC20" smd circle
			(at 6.5 9.5 90)
			(size 0.5 0.5)
			(layers "F.Cu" "F.Mask" "F.Paste")
			(net 1 "GND")
			(pinfunction "GND")
			(pintype "passive")
			(solder_mask_margin 0.075)
		)
		(pad "AC21" smd circle
			(at 7.5 9.5 90)
			(size 0.5 0.5)
			(layers "F.Cu" "F.Mask" "F.Paste")
			(net 153 "/DDR5 RDIMM/A.DQ23")
			(pinfunction "IO_L12N_T1U_N11_GC_64")
			(pintype "bidirectional")
			(die_length 13.25)
			(solder_mask_margin 0.075)
		)
		(pad "AC22" smd circle
			(at 8.5 9.5 90)
			(size 0.5 0.5)
			(layers "F.Cu" "F.Mask" "F.Paste")
			(net 145 "/DDR5 RDIMM/A.DQ18")
			(pinfunction "IO_L9P_T1L_N4_AD12P_64")
			(pintype "bidirectional")
			(die_length 12.927)
			(solder_mask_margin 0.075)
		)
		(pad "AC23" smd circle
			(at 9.5 9.5 90)
			(size 0.5 0.5)
			(layers "F.Cu" "F.Mask" "F.Paste")
			(net 146 "/DDR5 RDIMM/A.DQ19")
			(pinfunction "IO_L9N_T1L_N5_AD12N_64")
			(pintype "bidirectional")
			(die_length 13.489)
			(solder_mask_margin 0.075)
		)
		(pad "AC24" smd circle
			(at 10.5 9.5 90)
			(size 0.5 0.5)
			(layers "F.Cu" "F.Mask" "F.Paste")
			(net 66 "/DDR5 RDIMM/A.DQ29")
			(pinfunction "IO_L6N_T0U_N11_AD6N_64")
			(pintype "bidirectional")
			(die_length 13.512)
			(solder_mask_margin 0.075)
		)
		(pad "AC25" smd circle
			(at 11.5 9.5 90)
			(size 0.5 0.5)
			(layers "F.Cu" "F.Mask" "F.Paste")
			(net 1 "GND")
			(pinfunction "GND")
			(pintype "passive")
			(solder_mask_margin 0.075)
		)
		(pad "AC26" smd circle
			(at 12.5 9.5 90)
			(size 0.5 0.5)
			(layers "F.Cu" "F.Mask" "F.Paste")
			(net 216 "/DDR5 RDIMM/A.DQS8_P")
			(pinfunction "IO_L4P_T0U_N6_DBC_AD7P_64")
			(pintype "bidirectional")
			(die_length 15.88)
			(solder_mask_margin 0.075)
		)
		(pad "AD1" smd circle
			(at -12.5 10.5 90)
			(size 0.5 0.5)
			(layers "F.Cu" "F.Mask" "F.Paste")
			(net 586 "/FPGA MGT Interface/PCIE.RXD5_N")
			(pinfunction "MGTYRXN2_224")
			(pintype "input")
			(die_length 14.364)
			(solder_mask_margin 0.075)
		)
		(pad "AD2" smd circle
			(at -11.5 10.5 90)
			(size 0.5 0.5)
			(layers "F.Cu" "F.Mask" "F.Paste")
			(net 585 "/FPGA MGT Interface/PCIE.RXD5_P")
			(pinfunction "MGTYRXP2_224")
			(pintype "input")
			(die_length 14.346)
			(solder_mask_margin 0.075)
		)
		(pad "AD3" smd circle
			(at -10.5 10.5 90)
			(size 0.5 0.5)
			(layers "F.Cu" "F.Mask" "F.Paste")
			(net 1 "GND")
			(pinfunction "GND")
			(pintype "passive")
			(solder_mask_margin 0.075)
		)
		(pad "AD4" smd circle
			(at -9.5 10.5 90)
			(size 0.5 0.5)
			(layers "F.Cu" "F.Mask" "F.Paste")
			(net 1 "GND")
			(pinfunction "GND")
			(pintype "passive")
			(solder_mask_margin 0.075)
		)
		(pad "AD5" smd circle
			(at -8.5 10.5 90)
			(size 0.5 0.5)
			(layers "F.Cu" "F.Mask" "F.Paste")
			(net 1 "GND")
			(pinfunction "GND")
			(pintype "passive")
			(solder_mask_margin 0.075)
		)
		(pad "AD6" smd circle
			(at -7.5 10.5 90)
			(size 0.5 0.5)
			(layers "F.Cu" "F.Mask" "F.Paste")
			(net 470 "/FPGA MGT Interface/GTY_224_TX2_N")
			(pinfunction "MGTYTXN2_224")
			(pintype "output")
			(die_length 11.99)
			(solder_mask_margin 0.075)
		)
		(pad "AD7" smd circle
			(at -6.5 10.5 90)
			(size 0.5 0.5)
			(layers "F.Cu" "F.Mask" "F.Paste")
			(net 563 "/FPGA MGT Interface/GTY_224_TX2_P")
			(pinfunction "MGTYTXP2_224")
			(pintype "output")
			(die_length 12.01)
			(solder_mask_margin 0.075)
		)
		(pad "AD8" smd circle
			(at -5.5 10.5 90)
			(size 0.5 0.5)
			(layers "F.Cu" "F.Mask" "F.Paste")
			(net 172 "+1V2_MGTAVTT")
			(pinfunction "MGTAVTTRCAL_R")
			(pintype "input")
			(die_length 15.825)
			(solder_mask_margin 0.075)
		)
		(pad "AD9" smd circle
			(at -4.5 10.5 90)
			(size 0.5 0.5)
			(layers "F.Cu" "F.Mask" "F.Paste")
			(net 288 "Net-(U34L-MGTRREF_R)")
			(pinfunction "MGTRREF_R")
			(pintype "input")
			(die_length 15.768)
			(solder_mask_margin 0.075)
		)
		(pad "AD10" smd circle
			(at -3.5 10.5 90)
			(size 0.5 0.5)
			(layers "F.Cu" "F.Mask" "F.Paste")
			(net 1 "GND")
			(pinfunction "GND")
			(pintype "passive")
			(solder_mask_margin 0.075)
		)
		(pad "AD11" smd circle
			(at -2.5 10.5 90)
			(size 0.5 0.5)
			(layers "F.Cu" "F.Mask" "F.Paste")
			(net 351 "/FPGA Config/FLASH.IO0")
			(pinfunction "D00_MOSI_0")
			(pintype "bidirectional")
			(die_length 16.602)
			(solder_mask_margin 0.075)
		)
		(pad "AD12" smd circle
			(at -1.5 10.5 90)
			(size 0.5 0.5)
			(layers "F.Cu" "F.Mask" "F.Paste")
			(net 797 "+1V8")
			(pinfunction "VCCO_0")
			(pintype "passive")
			(solder_mask_margin 0.075)
		)
		(pad "AD13" smd circle
			(at -0.5 10.5 90)
			(size 0.5 0.5)
			(layers "F.Cu" "F.Mask" "F.Paste")
			(net 704 "~{DDR_PRESENCE}")
			(pinfunction "IO_L4P_AD8P_84")
			(pintype "bidirectional")
			(die_length 13.923)
			(solder_mask_margin 0.075)
		)
		(pad "AD14" smd circle
			(at 0.5 10.5 90)
			(size 0.5 0.5)
			(layers "F.Cu" "F.Mask" "F.Paste")
			(net 809 "VIN_MGMT_EN")
			(pinfunction "IO_L4N_AD8N_84")
			(pintype "bidirectional")
			(die_length 13.917)
			(solder_mask_margin 0.075)
		)
		(pad "AD15" smd circle
			(at 1.5 10.5 90)
			(size 0.5 0.5)
			(layers "F.Cu" "F.Mask" "F.Paste")
			(net 808 "VIN_BULK_EN")
			(pinfunction "IO_L3P_AD9P_84")
			(pintype "bidirectional")
			(die_length 12.603)
			(solder_mask_margin 0.075)
		)
		(pad "AD16" smd circle
			(at 2.5 10.5 90)
			(size 0.5 0.5)
			(layers "F.Cu" "F.Mask" "F.Paste")
			(net 58 "/DDR5 RDIMM/A.DQ13")
			(pinfunction "IO_L18P_T2U_N10_AD2P_64")
			(pintype "bidirectional")
			(die_length 17.061)
			(solder_mask_margin 0.075)
		)
		(pad "AD17" smd circle
			(at 3.5 10.5 90)
			(size 0.5 0.5)
			(layers "F.Cu" "F.Mask" "F.Paste")
			(net 1 "GND")
			(pinfunction "GND")
			(pintype "passive")
			(solder_mask_margin 0.075)
		)
		(pad "AD18" smd circle
			(at 4.5 10.5 90)
			(size 0.5 0.5)
			(layers "F.Cu" "F.Mask" "F.Paste")
			(net 181 "/DDR5 RDIMM/A.DQS6_N")
			(pinfunction "IO_L16N_T2U_N7_QBC_AD3N_64")
			(pintype "bidirectional")
			(die_length 15.07)
			(solder_mask_margin 0.075)
		)
		(pad "AD19" smd circle
			(at 5.5 10.5 90)
			(size 0.5 0.5)
			(layers "F.Cu" "F.Mask" "F.Paste")
			(net 140 "/DDR5 RDIMM/A.DQ11")
			(pinfunction "IO_L14N_T2L_N3_GC_64")
			(pintype "bidirectional")
			(die_length 14.076)
			(solder_mask_margin 0.075)
		)
		(pad "AD20" smd circle
			(at 6.5 10.5 90)
			(size 0.5 0.5)
			(layers "F.Cu" "F.Mask" "F.Paste")
			(net 102 "/DDR5 RDIMM/A.DQS1_P")
			(pinfunction "IO_L13P_T2L_N0_GC_QBC_64")
			(pintype "bidirectional")
			(die_length 15.279)
			(solder_mask_margin 0.075)
		)
		(pad "AD21" smd circle
			(at 7.5 10.5 90)
			(size 0.5 0.5)
			(layers "F.Cu" "F.Mask" "F.Paste")
			(net 61 "/DDR5 RDIMM/A.DQ20")
			(pinfunction "IO_L11P_T1U_N8_GC_64")
			(pintype "bidirectional")
			(die_length 14.797)
			(solder_mask_margin 0.075)
		)
		(pad "AD22" smd circle
			(at 8.5 10.5 90)
			(size 0.5 0.5)
			(layers "F.Cu" "F.Mask" "F.Paste")
			(net 687 "VDDQ")
			(pinfunction "VCCO_64")
			(pintype "passive")
			(solder_mask_margin 0.075)
		)
		(pad "AD23" smd circle
			(at 9.5 10.5 90)
			(size 0.5 0.5)
			(layers "F.Cu" "F.Mask" "F.Paste")
			(net 59 "/DDR5 RDIMM/A.DQ16")
			(pinfunction "IO_L8P_T1L_N2_AD5P_64")
			(pintype "bidirectional")
			(die_length 13.63)
			(solder_mask_margin 0.075)
		)
		(pad "AD24" smd circle
			(at 10.5 10.5 90)
			(size 0.5 0.5)
			(layers "F.Cu" "F.Mask" "F.Paste")
			(net 65 "/DDR5 RDIMM/A.DQ28")
			(pinfunction "IO_L5P_T0U_N8_AD14P_64")
			(pintype "bidirectional")
			(die_length 14.419)
			(solder_mask_margin 0.075)
		)
		(pad "AD25" smd circle
			(at 11.5 10.5 90)
			(size 0.5 0.5)
			(layers "F.Cu" "F.Mask" "F.Paste")
			(net 162 "/DDR5 RDIMM/A.DQ30")
			(pinfunction "IO_L5N_T0U_N9_AD14N_64")
			(pintype "bidirectional")
			(die_length 14.911)
			(solder_mask_margin 0.075)
		)
		(pad "AD26" smd circle
			(at 12.5 10.5 90)
			(size 0.5 0.5)
			(layers "F.Cu" "F.Mask" "F.Paste")
			(net 214 "/DDR5 RDIMM/A.DQS8_N")
			(pinfunction "IO_L4N_T0U_N7_DBC_AD7N_64")
			(pintype "bidirectional")
			(die_length 15.787)
			(solder_mask_margin 0.075)
		)
		(pad "AE1" smd circle
			(at -12.5 11.5 90)
			(size 0.5 0.5)
			(layers "F.Cu" "F.Mask" "F.Paste")
			(net 1 "GND")
			(pinfunction "GND")
			(pintype "passive")
			(solder_mask_margin 0.075)
		)
		(pad "AE2" smd circle
			(at -11.5 11.5 90)
			(size 0.5 0.5)
			(layers "F.Cu" "F.Mask" "F.Paste")
			(net 1 "GND")
			(pinfunction "GND")
			(pintype "passive")
			(solder_mask_margin 0.075)
		)
	)
)
